(kicad_pcb
	(version 20260206)
	(generator "pcbnew")
	(generator_version "10.0")
	(general
		(thickness 1.6)
		(legacy_teardrops no)
	)
	(paper "A4")
	(title_block
		(title "03242023_DA0F0TMBIJ0_F0T_Motherboard_J_brd_V01_OCP.brd")
		(comment 1 "Grand Teton / footprints 4336-4341 of 6105")
	)
	(layers
		(0 "F.Cu" signal "TOP")
		(4 "In1.Cu" signal "GND")
		(6 "In2.Cu" signal "IN1")
		(8 "In3.Cu" signal "GND1")
		(10 "In4.Cu" signal "IN2")
		(12 "In5.Cu" signal "GND2")
		(14 "In6.Cu" signal "IN3")
		(16 "In7.Cu" signal "GND3")
		(18 "In8.Cu" signal "VCC")
		(20 "In9.Cu" signal "VCC1")
		(22 "In10.Cu" signal "GND4")
		(24 "In11.Cu" signal "IN4")
		(26 "In12.Cu" signal "GND5")
		(28 "In13.Cu" signal "IN5")
		(30 "In14.Cu" signal "GND6")
		(32 "In15.Cu" signal "IN6")
		(34 "In16.Cu" signal "GND7")
		(2 "B.Cu" signal "BOTTOM")
		(9 "F.Adhes" user "F.Adhesive")
		(11 "B.Adhes" user "B.Adhesive")
		(13 "F.Paste" user "Package Geometry/Pastemask Top")
		(15 "B.Paste" user "Package Geometry/Pastemask Bottom")
		(5 "F.SilkS" user "Ref Des/Silkscreen Top")
		(7 "B.SilkS" user "Ref Des/Silkscreen Bottom")
		(1 "F.Mask" user "Board Geometry/Soldermask Top")
		(3 "B.Mask" user "Board Geometry/Soldermask Bottom")
		(17 "Dwgs.User" user "User.Drawings")
		(19 "Cmts.User" user "User.Comments")
		(21 "Eco1.User" user "User.Eco1")
		(23 "Eco2.User" user "User.Eco2")
		(25 "Edge.Cuts" user "Board Geometry/Outline")
		(27 "Margin" user)
		(31 "F.CrtYd" user "Package Geometry/Place Bound Top")
		(29 "B.CrtYd" user "Package Geometry/Place Bound Bottom")
		(35 "F.Fab" user "Ref Des/Assembly Top")
		(33 "B.Fab" user "Ref Des/Assembly Bottom")
	)
	(footprint ""
		(layer "B.Cu")
		(at 147.70608 -13.782548 90)
		(property "Reference" "R4088"
			(at 0 0 90)
			(layer "B.SilkS")
			(hide yes)
			(effects
				(font
					(size 1.27 1.27)
				)
				(justify mirror)
			)
		)
		(property "Value" ""
			(at 0 0 90)
			(layer "B.Fab")
			(effects
				(font
					(size 1.27 1.27)
				)
				(justify mirror)
			)
		)
		(duplicate_pad_numbers_are_jumpers no)
		(fp_line
			(start 0.7874 -0.4064)
			(end -0.7874 -0.4064)
			(stroke
				(width 0.1524)
				(type default)
			)
			(layer "B.SilkS")
		)
		(fp_line
			(start -0.7874 -0.4064)
			(end -0.7874 0.4064)
			(stroke
				(width 0.1524)
				(type default)
			)
			(layer "B.SilkS")
		)
		(fp_line
			(start 0.7874 0.4064)
			(end 0.7874 -0.4064)
			(stroke
				(width 0.1524)
				(type default)
			)
			(layer "B.SilkS")
		)
		(fp_line
			(start -0.7874 0.4064)
			(end 0.7874 0.4064)
			(stroke
				(width 0.1524)
				(type default)
			)
			(layer "B.SilkS")
		)
		(fp_line
			(start 0.67945 -0.305054)
			(end 0.12065 -0.305054)
			(stroke
				(width 0.1)
				(type default)
			)
			(layer "B.Fab")
		)
		(fp_line
			(start 0.12065 -0.305054)
			(end 0.12065 -0.2794)
			(stroke
				(width 0.1)
				(type default)
			)
			(layer "B.Fab")
		)
		(fp_line
			(start -0.12065 -0.3048)
			(end -0.67945 -0.3048)
			(stroke
				(width 0.1)
				(type default)
			)
			(layer "B.Fab")
		)
		(fp_line
			(start -0.67945 -0.3048)
			(end -0.67945 0.3048)
			(stroke
				(width 0.1)
				(type default)
			)
			(layer "B.Fab")
		)
		(fp_line
			(start 0.12065 -0.2794)
			(end -0.12065 -0.2794)
			(stroke
				(width 0.1)
				(type default)
			)
			(layer "B.Fab")
		)
		(fp_line
			(start -0.12065 -0.2794)
			(end -0.12065 -0.3048)
			(stroke
				(width 0.1)
				(type default)
			)
			(layer "B.Fab")
		)
		(fp_line
			(start 0.12065 0.2794)
			(end 0.12065 0.3048)
			(stroke
				(width 0.1)
				(type default)
			)
			(layer "B.Fab")
		)
		(fp_line
			(start -0.120396 0.2794)
			(end 0.12065 0.2794)
			(stroke
				(width 0.1)
				(type default)
			)
			(layer "B.Fab")
		)
		(fp_line
			(start 0.67945 0.3048)
			(end 0.67945 -0.305054)
			(stroke
				(width 0.1)
				(type default)
			)
			(layer "B.Fab")
		)
		(fp_line
			(start 0.12065 0.3048)
			(end 0.67945 0.3048)
			(stroke
				(width 0.1)
				(type default)
			)
			(layer "B.Fab")
		)
		(fp_line
			(start -0.120396 0.3048)
			(end -0.120396 0.2794)
			(stroke
				(width 0.1)
				(type default)
			)
			(layer "B.Fab")
		)
		(fp_line
			(start -0.67945 0.3048)
			(end -0.120396 0.3048)
			(stroke
				(width 0.1)
				(type default)
			)
			(layer "B.Fab")
		)
		(pad "1" smd circle
			(at 0.40005 0 270)
			(size 0 0)
			(layers "B.Cu" "B.Mask" "B.Paste")
			(net "FM_JTAG_BMC_MUX_SEL_FROM_BMC_R")
		)
		(pad "2" smd circle
			(at -0.40005 0 270)
			(size 0 0)
			(layers "B.Cu" "B.Mask" "B.Paste")
			(net "FM_JTAG_BMC_MUX_SEL")
		)
	)
	(footprint ""
		(layer "B.Cu")
		(at 179.755546 -110.975394 -90)
		(property "Reference" "C1113"
			(at 0 0 90)
			(layer "B.SilkS")
			(hide yes)
			(effects
				(font
					(size 1.27 1.27)
				)
				(justify mirror)
			)
		)
		(property "Value" ""
			(at 0 0 90)
			(layer "B.Fab")
			(effects
				(font
					(size 1.27 1.27)
				)
				(justify mirror)
			)
		)
		(duplicate_pad_numbers_are_jumpers no)
		(fp_line
			(start -0.69215 0.2921)
			(end 0.69215 0.2921)
			(stroke
				(width 0.1524)
				(type default)
			)
			(layer "B.SilkS")
		)
		(fp_line
			(start 0.69215 0.2921)
			(end 0.69215 -0.2921)
			(stroke
				(width 0.1524)
				(type default)
			)
			(layer "B.SilkS")
		)
		(fp_line
			(start -0.69215 -0.2921)
			(end -0.69215 0.2921)
			(stroke
				(width 0.1524)
				(type default)
			)
			(layer "B.SilkS")
		)
		(fp_line
			(start 0.69215 -0.2921)
			(end -0.69215 -0.2921)
			(stroke
				(width 0.1524)
				(type default)
			)
			(layer "B.SilkS")
		)
		(fp_line
			(start -0.51435 0.2794)
			(end 0.51435 0.2794)
			(stroke
				(width 0.1)
				(type default)
			)
			(layer "B.Fab")
		)
		(fp_line
			(start 0.51435 0.2794)
			(end 0.51435 -0.2794)
			(stroke
				(width 0.1)
				(type default)
			)
			(layer "B.Fab")
		)
		(fp_line
			(start -0.51435 -0.2794)
			(end -0.51435 0.2794)
			(stroke
				(width 0.1)
				(type default)
			)
			(layer "B.Fab")
		)
		(fp_line
			(start 0.51435 -0.2794)
			(end -0.51435 -0.2794)
			(stroke
				(width 0.1)
				(type default)
			)
			(layer "B.Fab")
		)
		(pad "1" smd circle
			(at 0.40005 0 90)
			(size 0 0)
			(layers "B.Cu" "B.Mask" "B.Paste")
			(net "P3V3_AUX_FPGA_VCCIO3")
		)
		(pad "2" smd circle
			(at -0.40005 0 90)
			(size 0 0)
			(layers "B.Cu" "B.Mask" "B.Paste")
			(net "GND")
		)
		(zone
			(layer "B.Cu")
			(hatch none 0.5)
			(connect_pads
				(clearance 0)
			)
			(min_thickness 0.25)
			(keepout
				(tracks not_allowed)
				(vias allowed)
				(pads allowed)
				(copperpour not_allowed)
				(footprints allowed)
			)
			(placement
				(enabled no)
				(sheetname "")
			)
			(fill
				(thermal_gap 0.5)
				(thermal_bridge_width 0.5)
				(island_removal_mode 0)
			)
			(polygon
				(pts
					(xy 179.667916 -110.784894) (xy 179.60975 -110.876334) (xy 179.60975 -111.075724) (xy 179.667916 -111.165894)
					(xy 179.843176 -111.165894) (xy 179.901596 -111.075724) (xy 179.901596 -110.876334) (xy 179.84343 -110.784894)
				)
			)
		)
	)
	(footprint ""
		(layer "B.Cu")
		(at 157.02788 -9.830308)
		(property "Reference" "R588"
			(at 0 0 0)
			(layer "B.SilkS")
			(hide yes)
			(effects
				(font
					(size 1.27 1.27)
				)
				(justify mirror)
			)
		)
		(property "Value" ""
			(at 0 0 0)
			(layer "B.Fab")
			(effects
				(font
					(size 1.27 1.27)
				)
				(justify mirror)
			)
		)
		(duplicate_pad_numbers_are_jumpers no)
		(fp_line
			(start -0.7874 -0.4064)
			(end -0.7874 0.4064)
			(stroke
				(width 0.1524)
				(type default)
			)
			(layer "B.SilkS")
		)
		(fp_line
			(start -0.7874 0.4064)
			(end 0.7874 0.4064)
			(stroke
				(width 0.1524)
				(type default)
			)
			(layer "B.SilkS")
		)
		(fp_line
			(start 0.7874 -0.4064)
			(end -0.7874 -0.4064)
			(stroke
				(width 0.1524)
				(type default)
			)
			(layer "B.SilkS")
		)
		(fp_line
			(start 0.7874 0.4064)
			(end 0.7874 -0.4064)
			(stroke
				(width 0.1524)
				(type default)
			)
			(layer "B.SilkS")
		)
		(fp_line
			(start -0.67945 -0.3048)
			(end -0.67945 0.3048)
			(stroke
				(width 0.1)
				(type default)
			)
			(layer "B.Fab")
		)
		(fp_line
			(start -0.67945 0.3048)
			(end -0.120396 0.3048)
			(stroke
				(width 0.1)
				(type default)
			)
			(layer "B.Fab")
		)
		(fp_line
			(start -0.12065 -0.3048)
			(end -0.67945 -0.3048)
			(stroke
				(width 0.1)
				(type default)
			)
			(layer "B.Fab")
		)
		(fp_line
			(start -0.12065 -0.2794)
			(end -0.12065 -0.3048)
			(stroke
				(width 0.1)
				(type default)
			)
			(layer "B.Fab")
		)
		(fp_line
			(start -0.120396 0.2794)
			(end 0.12065 0.2794)
			(stroke
				(width 0.1)
				(type default)
			)
			(layer "B.Fab")
		)
		(fp_line
			(start -0.120396 0.3048)
			(end -0.120396 0.2794)
			(stroke
				(width 0.1)
				(type default)
			)
			(layer "B.Fab")
		)
		(fp_line
			(start 0.12065 -0.305054)
			(end 0.12065 -0.2794)
			(stroke
				(width 0.1)
				(type default)
			)
			(layer "B.Fab")
		)
		(fp_line
			(start 0.12065 -0.2794)
			(end -0.12065 -0.2794)
			(stroke
				(width 0.1)
				(type default)
			)
			(layer "B.Fab")
		)
		(fp_line
			(start 0.12065 0.2794)
			(end 0.12065 0.3048)
			(stroke
				(width 0.1)
				(type default)
			)
			(layer "B.Fab")
		)
		(fp_line
			(start 0.12065 0.3048)
			(end 0.67945 0.3048)
			(stroke
				(width 0.1)
				(type default)
			)
			(layer "B.Fab")
		)
		(fp_line
			(start 0.67945 -0.305054)
			(end 0.12065 -0.305054)
			(stroke
				(width 0.1)
				(type default)
			)
			(layer "B.Fab")
		)
		(fp_line
			(start 0.67945 0.3048)
			(end 0.67945 -0.305054)
			(stroke
				(width 0.1)
				(type default)
			)
			(layer "B.Fab")
		)
		(pad "1" smd circle
			(at 0.40005 0 180)
			(size 0 0)
			(layers "B.Cu" "B.Mask" "B.Paste")
			(net "SMB_PCIE0_3V3AUX_SCL")
		)
		(pad "2" smd circle
			(at -0.40005 0 180)
			(size 0 0)
			(layers "B.Cu" "B.Mask" "B.Paste")
			(net "SMB_PCIE0_3V3AUX_SCL_R")
		)
	)
	(footprint ""
		(layer "B.Cu")
		(at 312.13044 -193.74231 -90)
		(property "Reference" "R276"
			(at 0 0 90)
			(layer "B.SilkS")
			(hide yes)
			(effects
				(font
					(size 1.27 1.27)
				)
				(justify mirror)
			)
		)
		(property "Value" ""
			(at 0 0 90)
			(layer "B.Fab")
			(effects
				(font
					(size 1.27 1.27)
				)
				(justify mirror)
			)
		)
		(duplicate_pad_numbers_are_jumpers no)
		(fp_line
			(start -0.7874 0.4064)
			(end 0.7874 0.4064)
			(stroke
				(width 0.1524)
				(type default)
			)
			(layer "B.SilkS")
		)
		(fp_line
			(start 0.7874 0.4064)
			(end 0.7874 -0.4064)
			(stroke
				(width 0.1524)
				(type default)
			)
			(layer "B.SilkS")
		)
		(fp_line
			(start -0.7874 -0.4064)
			(end -0.7874 0.4064)
			(stroke
				(width 0.1524)
				(type default)
			)
			(layer "B.SilkS")
		)
		(fp_line
			(start 0.7874 -0.4064)
			(end -0.7874 -0.4064)
			(stroke
				(width 0.1524)
				(type default)
			)
			(layer "B.SilkS")
		)
		(fp_line
			(start -0.67945 0.3048)
			(end -0.120396 0.3048)
			(stroke
				(width 0.1)
				(type default)
			)
			(layer "B.Fab")
		)
		(fp_line
			(start -0.120396 0.3048)
			(end -0.120396 0.2794)
			(stroke
				(width 0.1)
				(type default)
			)
			(layer "B.Fab")
		)
		(fp_line
			(start 0.12065 0.3048)
			(end 0.67945 0.3048)
			(stroke
				(width 0.1)
				(type default)
			)
			(layer "B.Fab")
		)
		(fp_line
			(start 0.67945 0.3048)
			(end 0.67945 -0.305054)
			(stroke
				(width 0.1)
				(type default)
			)
			(layer "B.Fab")
		)
		(fp_line
			(start -0.120396 0.2794)
			(end 0.12065 0.2794)
			(stroke
				(width 0.1)
				(type default)
			)
			(layer "B.Fab")
		)
		(fp_line
			(start 0.12065 0.2794)
			(end 0.12065 0.3048)
			(stroke
				(width 0.1)
				(type default)
			)
			(layer "B.Fab")
		)
		(fp_line
			(start -0.12065 -0.2794)
			(end -0.12065 -0.3048)
			(stroke
				(width 0.1)
				(type default)
			)
			(layer "B.Fab")
		)
		(fp_line
			(start 0.12065 -0.2794)
			(end -0.12065 -0.2794)
			(stroke
				(width 0.1)
				(type default)
			)
			(layer "B.Fab")
		)
		(fp_line
			(start -0.67945 -0.3048)
			(end -0.67945 0.3048)
			(stroke
				(width 0.1)
				(type default)
			)
			(layer "B.Fab")
		)
		(fp_line
			(start -0.12065 -0.3048)
			(end -0.67945 -0.3048)
			(stroke
				(width 0.1)
				(type default)
			)
			(layer "B.Fab")
		)
		(fp_line
			(start 0.12065 -0.305054)
			(end 0.12065 -0.2794)
			(stroke
				(width 0.1)
				(type default)
			)
			(layer "B.Fab")
		)
		(fp_line
			(start 0.67945 -0.305054)
			(end 0.12065 -0.305054)
			(stroke
				(width 0.1)
				(type default)
			)
			(layer "B.Fab")
		)
		(pad "1" smd circle
			(at 0.40005 0 90)
			(size 0 0)
			(layers "B.Cu" "B.Mask" "B.Paste")
			(net "PVNN_TERM_CPU0")
		)
		(pad "2" smd circle
			(at -0.40005 0 90)
			(size 0 0)
			(layers "B.Cu" "B.Mask" "B.Paste")
			(net "PU_CPU0_SAFE_MODE_BOOT")
		)
	)
	(footprint ""
		(layer "B.Cu")
		(at 291.964618 -149.992588 -90)
		(property "Reference" "R87"
			(at 0 0 90)
			(layer "B.SilkS")
			(hide yes)
			(effects
				(font
					(size 1.27 1.27)
				)
				(justify mirror)
			)
		)
		(property "Value" ""
			(at 0 0 90)
			(layer "B.Fab")
			(effects
				(font
					(size 1.27 1.27)
				)
				(justify mirror)
			)
		)
		(duplicate_pad_numbers_are_jumpers no)
		(fp_line
			(start -0.7874 0.4064)
			(end 0.7874 0.4064)
			(stroke
				(width 0.1524)
				(type default)
			)
			(layer "B.SilkS")
		)
		(fp_line
			(start 0.7874 0.4064)
			(end 0.7874 -0.4064)
			(stroke
				(width 0.1524)
				(type default)
			)
			(layer "B.SilkS")
		)
		(fp_line
			(start -0.7874 -0.4064)
			(end -0.7874 0.4064)
			(stroke
				(width 0.1524)
				(type default)
			)
			(layer "B.SilkS")
		)
		(fp_line
			(start 0.7874 -0.4064)
			(end -0.7874 -0.4064)
			(stroke
				(width 0.1524)
				(type default)
			)
			(layer "B.SilkS")
		)
		(fp_line
			(start -0.67945 0.3048)
			(end -0.120396 0.3048)
			(stroke
				(width 0.1)
				(type default)
			)
			(layer "B.Fab")
		)
		(fp_line
			(start -0.120396 0.3048)
			(end -0.120396 0.2794)
			(stroke
				(width 0.1)
				(type default)
			)
			(layer "B.Fab")
		)
		(fp_line
			(start 0.12065 0.3048)
			(end 0.67945 0.3048)
			(stroke
				(width 0.1)
				(type default)
			)
			(layer "B.Fab")
		)
		(fp_line
			(start 0.67945 0.3048)
			(end 0.67945 -0.305054)
			(stroke
				(width 0.1)
				(type default)
			)
			(layer "B.Fab")
		)
		(fp_line
			(start -0.120396 0.2794)
			(end 0.12065 0.2794)
			(stroke
				(width 0.1)
				(type default)
			)
			(layer "B.Fab")
		)
		(fp_line
			(start 0.12065 0.2794)
			(end 0.12065 0.3048)
			(stroke
				(width 0.1)
				(type default)
			)
			(layer "B.Fab")
		)
		(fp_line
			(start -0.12065 -0.2794)
			(end -0.12065 -0.3048)
			(stroke
				(width 0.1)
				(type default)
			)
			(layer "B.Fab")
		)
		(fp_line
			(start 0.12065 -0.2794)
			(end -0.12065 -0.2794)
			(stroke
				(width 0.1)
				(type default)
			)
			(layer "B.Fab")
		)
		(fp_line
			(start -0.67945 -0.3048)
			(end -0.67945 0.3048)
			(stroke
				(width 0.1)
				(type default)
			)
			(layer "B.Fab")
		)
		(fp_line
			(start -0.12065 -0.3048)
			(end -0.67945 -0.3048)
			(stroke
				(width 0.1)
				(type default)
			)
			(layer "B.Fab")
		)
		(fp_line
			(start 0.12065 -0.305054)
			(end 0.12065 -0.2794)
			(stroke
				(width 0.1)
				(type default)
			)
			(layer "B.Fab")
		)
		(fp_line
			(start 0.67945 -0.305054)
			(end 0.12065 -0.305054)
			(stroke
				(width 0.1)
				(type default)
			)
			(layer "B.Fab")
		)
		(pad "1" smd circle
			(at 0.40005 0 90)
			(size 0 0)
			(layers "B.Cu" "B.Mask" "B.Paste")
			(net "P3V3_AUX")
		)
		(pad "2" smd circle
			(at -0.40005 0 90)
			(size 0 0)
			(layers "B.Cu" "B.Mask" "B.Paste")
			(net "FM_SPD_REMOTE_EN")
		)
	)
	(footprint ""
		(layer "B.Cu")
		(at 93.193108 -190.705232 90)
		(property "Reference" "R670"
			(at 0 0 90)
			(layer "B.SilkS")
			(hide yes)
			(effects
				(font
					(size 1.27 1.27)
				)
				(justify mirror)
			)
		)
		(property "Value" ""
			(at 0 0 90)
			(layer "B.Fab")
			(effects
				(font
					(size 1.27 1.27)
				)
				(justify mirror)
			)
		)
		(duplicate_pad_numbers_are_jumpers no)
		(fp_line
			(start 0.7874 -0.4064)
			(end -0.7874 -0.4064)
			(stroke
				(width 0.1524)
				(type default)
			)
			(layer "B.SilkS")
		)
		(fp_line
			(start -0.7874 -0.4064)
			(end -0.7874 0.4064)
			(stroke
				(width 0.1524)
				(type default)
			)
			(layer "B.SilkS")
		)
		(fp_line
			(start 0.7874 0.4064)
			(end 0.7874 -0.4064)
			(stroke
				(width 0.1524)
				(type default)
			)
			(layer "B.SilkS")
		)
		(fp_line
			(start -0.7874 0.4064)
			(end 0.7874 0.4064)
			(stroke
				(width 0.1524)
				(type default)
			)
			(layer "B.SilkS")
		)
		(fp_line
			(start 0.67945 -0.305054)
			(end 0.12065 -0.305054)
			(stroke
				(width 0.1)
				(type default)
			)
			(layer "B.Fab")
		)
		(fp_line
			(start 0.12065 -0.305054)
			(end 0.12065 -0.2794)
			(stroke
				(width 0.1)
				(type default)
			)
			(layer "B.Fab")
		)
		(fp_line
			(start -0.12065 -0.3048)
			(end -0.67945 -0.3048)
			(stroke
				(width 0.1)
				(type default)
			)
			(layer "B.Fab")
		)
		(fp_line
			(start -0.67945 -0.3048)
			(end -0.67945 0.3048)
			(stroke
				(width 0.1)
				(type default)
			)
			(layer "B.Fab")
		)
		(fp_line
			(start 0.12065 -0.2794)
			(end -0.12065 -0.2794)
			(stroke
				(width 0.1)
				(type default)
			)
			(layer "B.Fab")
		)
		(fp_line
			(start -0.12065 -0.2794)
			(end -0.12065 -0.3048)
			(stroke
				(width 0.1)
				(type default)
			)
			(layer "B.Fab")
		)
		(fp_line
			(start 0.12065 0.2794)
			(end 0.12065 0.3048)
			(stroke
				(width 0.1)
				(type default)
			)
			(layer "B.Fab")
		)
		(fp_line
			(start -0.120396 0.2794)
			(end 0.12065 0.2794)
			(stroke
				(width 0.1)
				(type default)
			)
			(layer "B.Fab")
		)
		(fp_line
			(start 0.67945 0.3048)
			(end 0.67945 -0.305054)
			(stroke
				(width 0.1)
				(type default)
			)
			(layer "B.Fab")
		)
		(fp_line
			(start 0.12065 0.3048)
			(end 0.67945 0.3048)
			(stroke
				(width 0.1)
				(type default)
			)
			(layer "B.Fab")
		)
		(fp_line
			(start -0.120396 0.3048)
			(end -0.120396 0.2794)
			(stroke
				(width 0.1)
				(type default)
			)
			(layer "B.Fab")
		)
		(fp_line
			(start -0.67945 0.3048)
			(end -0.120396 0.3048)
			(stroke
				(width 0.1)
				(type default)
			)
			(layer "B.Fab")
		)
		(pad "1" smd circle
			(at 0.40005 0 270)
			(size 0 0)
			(layers "B.Cu" "B.Mask" "B.Paste")
			(net "I3C_SPD_DDRABCD_CPU1_SCL")
		)
		(pad "2" smd circle
			(at -0.40005 0 270)
			(size 0 0)
			(layers "B.Cu" "B.Mask" "B.Paste")
			(net "I3C_SPD_DDRABCD_CPU1_R_SCL")
		)
	)
)
